(kicad_pcb
	(version 20260206)
	(generator "pcbnew")
	(generator_version "10.0")
	(general
		(thickness 1.6)
		(legacy_teardrops no)
	)
	(paper "A4")
	(title_block
		(title "Wiwynn_Tioga_Pass_MB.brd")
		(comment 1 "Tioga Pass / footprints 4716-4722 of 4770")
	)
	(layers
		(0 "F.Cu" signal "TOP")
		(4 "In1.Cu" signal "L2GND")
		(6 "In2.Cu" signal "L3")
		(8 "In3.Cu" signal "L4GND")
		(10 "In4.Cu" signal "L5")
		(12 "In5.Cu" signal "L6GND")
		(14 "In6.Cu" signal "L7VCC")
		(16 "In7.Cu" signal "L8VCC")
		(18 "In8.Cu" signal "L9GND")
		(20 "In9.Cu" signal "L10")
		(22 "In10.Cu" signal "L11GND")
		(24 "In11.Cu" signal "L12")
		(26 "In12.Cu" signal "L13GND")
		(2 "B.Cu" signal "BOTTOM")
		(9 "F.Adhes" user "F.Adhesive")
		(11 "B.Adhes" user "B.Adhesive")
		(13 "F.Paste" user "Package Geometry/Pastemask Top")
		(15 "B.Paste" user "Package Geometry/Pastemask Bottom")
		(5 "F.SilkS" user "Ref Des/Silkscreen Top")
		(7 "B.SilkS" user "Ref Des/Silkscreen Bottom")
		(1 "F.Mask" user "Board Geometry/Soldermask Top")
		(3 "B.Mask" user "Board Geometry/Soldermask Bottom")
		(17 "Dwgs.User" user "User.Drawings")
		(19 "Cmts.User" user "User.Comments")
		(21 "Eco1.User" user "User.Eco1")
		(23 "Eco2.User" user "User.Eco2")
		(25 "Edge.Cuts" user "Board Geometry/Outline")
		(27 "Margin" user)
		(31 "F.CrtYd" user "Package Geometry/Place Bound Top")
		(29 "B.CrtYd" user "Package Geometry/Place Bound Bottom")
		(35 "F.Fab" user "Ref Des/Assembly Top")
		(33 "B.Fab" user "Ref Des/Assembly Bottom")
	)
	(footprint ""
		(layer "B.Cu")
		(at 388.66064 -80.2386 -90)
		(property "Reference" "R3P63"
			(at 0.8382 -0.67818 270)
			(unlocked yes)
			(layer "B.SilkS")
			(effects
				(font
					(size 0.4064 0.254)
					(thickness 0.1524)
				)
				(justify left mirror)
			)
		)
		(property "Value" ""
			(at 0 0 90)
			(layer "B.Fab")
			(effects
				(font
					(size 1.27 1.27)
				)
				(justify mirror)
			)
		)
		(duplicate_pad_numbers_are_jumpers no)
		(fp_poly
			(pts
				(xy 0.2794 -0.1016) (xy -0.2794 -0.1016) (xy -0.2794 0.9906) (xy 0.2794 0.9906)
			)
			(stroke
				(width 0)
				(type default)
			)
			(fill no)
			(layer "B.CrtYd")
		)
		(fp_line
			(start -0.2794 0.9906)
			(end -0.2794 -0.1016)
			(stroke
				(width 0.1)
				(type default)
			)
			(layer "B.Fab")
		)
		(fp_line
			(start 0.2794 0.9906)
			(end -0.2794 0.9906)
			(stroke
				(width 0.1)
				(type default)
			)
			(layer "B.Fab")
		)
		(fp_line
			(start -0.2794 -0.1016)
			(end 0.2794 -0.1016)
			(stroke
				(width 0.1)
				(type default)
			)
			(layer "B.Fab")
		)
		(fp_line
			(start 0.2794 -0.1016)
			(end 0.2794 0.9906)
			(stroke
				(width 0.1)
				(type default)
			)
			(layer "B.Fab")
		)
		(pad "1" smd rect
			(at 0 0 90)
			(size 0.508 0.508)
			(layers "B.Cu" "B.Mask" "B.Paste")
			(net "H_CPU1_MEMGHJ_MEMHOT_LVT3_N")
		)
		(pad "2" smd rect
			(at 0 0.889 90)
			(size 0.508 0.508)
			(layers "B.Cu" "B.Mask" "B.Paste")
			(net "H_CPU1_MEMGHJ_MEMHOT_PCH_N")
		)
		(zone
			(layer "B.Cu")
			(hatch none 0.5)
			(connect_pads
				(clearance 0)
			)
			(min_thickness 0.25)
			(keepout
				(tracks not_allowed)
				(vias allowed)
				(pads allowed)
				(copperpour not_allowed)
				(footprints allowed)
			)
			(placement
				(enabled no)
				(sheetname "")
			)
			(fill
				(thermal_gap 0.5)
				(thermal_bridge_width 0.5)
				(island_removal_mode 0)
			)
			(polygon
				(pts
					(xy 388.02564 -79.9846) (xy 388.02564 -80.4926) (xy 388.40664 -80.4926) (xy 388.40664 -79.9846)
				)
			)
		)
		(zone
			(layer "B.Cu")
			(hatch none 0.5)
			(connect_pads
				(clearance 0)
			)
			(min_thickness 0.25)
			(keepout
				(tracks allowed)
				(vias not_allowed)
				(pads allowed)
				(copperpour not_allowed)
				(footprints allowed)
			)
			(placement
				(enabled no)
				(sheetname "")
			)
			(fill
				(thermal_gap 0.5)
				(thermal_bridge_width 0.5)
				(island_removal_mode 0)
			)
			(polygon
				(pts
					(xy 388.40664 -79.9846) (xy 388.40664 -80.4926) (xy 388.02564 -80.4926) (xy 388.02564 -79.9846)
				)
			)
		)
	)
	(footprint ""
		(layer "B.Cu")
		(at 488.95 -15.748)
		(property "Reference" ""
			(at 0 0 0)
			(layer "B.SilkS")
			(hide yes)
			(effects
				(font
					(size 1.27 1.27)
				)
				(justify mirror)
			)
		)
		(property "Value" ""
			(at 0 0 0)
			(layer "B.Fab")
			(effects
				(font
					(size 1.27 1.27)
				)
				(justify mirror)
			)
		)
		(duplicate_pad_numbers_are_jumpers no)
		(fp_poly
			(pts
				(arc
					(start 2.032 0)
					(mid -2.032 0)
					(end 2.032 0)
				)
			)
			(stroke
				(width 0)
				(type default)
			)
			(fill no)
			(layer "B.CrtYd")
		)
		(pad "1" smd circle
			(at 0 0 180)
			(size 1.016 1.016)
			(layers "B.Cu" "B.Mask" "B.Paste")
			(net "Net_128")
		)
		(zone
			(layers "F.Cu" "B.Cu" "In1.Cu" "In2.Cu" "In3.Cu" "In4.Cu" "In5.Cu" "In6.Cu"
				"In7.Cu" "In8.Cu" "In9.Cu" "In10.Cu" "In11.Cu" "In12.Cu"
			)
			(hatch none 0.5)
			(connect_pads
				(clearance 0)
			)
			(min_thickness 0.25)
			(keepout
				(tracks allowed)
				(vias not_allowed)
				(pads allowed)
				(copperpour not_allowed)
				(footprints allowed)
			)
			(placement
				(enabled no)
				(sheetname "")
			)
			(fill
				(thermal_gap 0.5)
				(thermal_bridge_width 0.5)
				(island_removal_mode 0)
			)
			(polygon
				(pts
					(arc
						(start 490.474 -15.748)
						(mid 487.426 -15.748)
						(end 490.474 -15.748)
					)
				)
			)
		)
		(zone
			(layer "B.Cu")
			(hatch none 0.5)
			(connect_pads
				(clearance 0)
			)
			(min_thickness 0.25)
			(keepout
				(tracks not_allowed)
				(vias allowed)
				(pads allowed)
				(copperpour not_allowed)
				(footprints allowed)
			)
			(placement
				(enabled no)
				(sheetname "")
			)
			(fill
				(thermal_gap 0.5)
				(thermal_bridge_width 0.5)
				(island_removal_mode 0)
			)
			(polygon
				(pts
					(arc
						(start 490.474 -15.748)
						(mid 487.426 -15.748)
						(end 490.474 -15.748)
					)
				)
			)
		)
	)
	(footprint ""
		(layer "B.Cu")
		(at 371.983 -65.6844 180)
		(property "Reference" "R4W1"
			(at 0.8382 -0.67818 180)
			(unlocked yes)
			(layer "B.SilkS")
			(effects
				(font
					(size 0.4064 0.254)
					(thickness 0.1524)
				)
				(justify left mirror)
			)
		)
		(property "Value" ""
			(at 0 0 0)
			(layer "B.Fab")
			(effects
				(font
					(size 1.27 1.27)
				)
				(justify mirror)
			)
		)
		(duplicate_pad_numbers_are_jumpers no)
		(fp_poly
			(pts
				(xy 0.2794 -0.1016) (xy -0.2794 -0.1016) (xy -0.2794 0.9906) (xy 0.2794 0.9906)
			)
			(stroke
				(width 0)
				(type default)
			)
			(fill no)
			(layer "B.CrtYd")
		)
		(fp_line
			(start 0.2794 0.9906)
			(end -0.2794 0.9906)
			(stroke
				(width 0.1)
				(type default)
			)
			(layer "B.Fab")
		)
		(fp_line
			(start 0.2794 -0.1016)
			(end 0.2794 0.9906)
			(stroke
				(width 0.1)
				(type default)
			)
			(layer "B.Fab")
		)
		(fp_line
			(start -0.2794 0.9906)
			(end -0.2794 -0.1016)
			(stroke
				(width 0.1)
				(type default)
			)
			(layer "B.Fab")
		)
		(fp_line
			(start -0.2794 -0.1016)
			(end 0.2794 -0.1016)
			(stroke
				(width 0.1)
				(type default)
			)
			(layer "B.Fab")
		)
		(pad "1" smd rect
			(at 0 0)
			(size 0.508 0.508)
			(layers "B.Cu" "B.Mask" "B.Paste")
			(net "P3V3_STBY")
		)
		(pad "2" smd rect
			(at 0 0.889)
			(size 0.508 0.508)
			(layers "B.Cu" "B.Mask" "B.Paste")
			(net "PU_CPLD1_PT20D_PROGRAMN")
		)
		(zone
			(layer "B.Cu")
			(hatch none 0.5)
			(connect_pads
				(clearance 0)
			)
			(min_thickness 0.25)
			(keepout
				(tracks not_allowed)
				(vias allowed)
				(pads allowed)
				(copperpour not_allowed)
				(footprints allowed)
			)
			(placement
				(enabled no)
				(sheetname "")
			)
			(fill
				(thermal_gap 0.5)
				(thermal_bridge_width 0.5)
				(island_removal_mode 0)
			)
			(polygon
				(pts
					(xy 371.729 -66.3194) (xy 372.237 -66.3194) (xy 372.237 -65.9384) (xy 371.729 -65.9384)
				)
			)
		)
		(zone
			(layer "B.Cu")
			(hatch none 0.5)
			(connect_pads
				(clearance 0)
			)
			(min_thickness 0.25)
			(keepout
				(tracks allowed)
				(vias not_allowed)
				(pads allowed)
				(copperpour not_allowed)
				(footprints allowed)
			)
			(placement
				(enabled no)
				(sheetname "")
			)
			(fill
				(thermal_gap 0.5)
				(thermal_bridge_width 0.5)
				(island_removal_mode 0)
			)
			(polygon
				(pts
					(xy 371.729 -65.9384) (xy 372.237 -65.9384) (xy 372.237 -66.3194) (xy 371.729 -66.3194)
				)
			)
		)
	)
	(footprint ""
		(layer "B.Cu")
		(at 11.6332 -128.8034 90)
		(property "Reference" "R12W18"
			(at 0 0 90)
			(layer "B.SilkS")
			(hide yes)
			(effects
				(font
					(size 1.27 1.27)
				)
				(justify mirror)
			)
		)
		(property "Value" "*"
			(at -0.064008 -4.108196 90)
			(unlocked yes)
			(layer "B.Fab")
			(hide yes)
			(effects
				(font
					(size 1.27 1.016)
					(thickness 0.1524)
				)
				(justify mirror)
			)
		)
		(property "Device Type" "4D02R2F-GP_SMD-RG2-4D02R2F-GP,A"
			(at -0.064008 -5.632196 90)
			(unlocked yes)
			(layer "B.Fab")
			(hide yes)
			(effects
				(font
					(size 1.27 1.016)
					(thickness 0.1524)
				)
				(justify mirror)
			)
		)
		(duplicate_pad_numbers_are_jumpers no)
		(fp_line
			(start 0.508 -0.9398)
			(end 0.508 0.9398)
			(stroke
				(width 0.1524)
				(type default)
			)
			(layer "B.SilkS")
		)
		(fp_line
			(start -0.508 -0.9398)
			(end 0.508 -0.9398)
			(stroke
				(width 0.1524)
				(type default)
			)
			(layer "B.SilkS")
		)
		(fp_rect
			(start 0.508 0.9398)
			(end -0.508 -0.9398)
			(stroke
				(width 0)
				(type default)
			)
			(fill no)
			(layer "B.CrtYd")
		)
		(fp_rect
			(start 0.508 0.9398)
			(end -0.508 -0.9398)
			(stroke
				(width 0)
				(type default)
			)
			(fill no)
			(layer "B.Fab")
		)
		(pad "1" smd custom
			(at 0 -0.4445 270)
			(size 0.1397 0.1397)
			(layers "B.Cu" "B.Mask" "B.Paste")
			(net "P12V_STBY")
			(options
				(clearance outline)
				(anchor circle)
			)
			(primitives
				(gr_poly
					(pts
						(arc
							(start -0.1778 0.2794)
							(mid -0.249642 0.249642)
							(end -0.2794 0.1778)
						)
						(arc
							(start -0.2794 -0.1778)
							(mid -0.249642 -0.249642)
							(end -0.1778 -0.2794)
						)
						(arc
							(start 0.1778 -0.2794)
							(mid 0.249642 -0.249642)
							(end 0.2794 -0.1778)
						)
						(arc
							(start 0.2794 0.1778)
							(mid 0.249642 0.249642)
							(end 0.1778 0.2794)
						)
					)
					(width 0)
					(fill yes)
				)
			)
		)
		(pad "2" smd custom
			(at 0 0.4445 270)
			(size 0.1397 0.1397)
			(layers "B.Cu" "B.Mask" "B.Paste")
			(net "P12V_NVDIMM_KLM_D")
			(options
				(clearance outline)
				(anchor circle)
			)
			(primitives
				(gr_poly
					(pts
						(arc
							(start -0.1778 0.2794)
							(mid -0.249642 0.249642)
							(end -0.2794 0.1778)
						)
						(arc
							(start -0.2794 -0.1778)
							(mid -0.249642 -0.249642)
							(end -0.1778 -0.2794)
						)
						(arc
							(start 0.1778 -0.2794)
							(mid 0.249642 -0.249642)
							(end 0.2794 -0.1778)
						)
						(arc
							(start 0.2794 0.1778)
							(mid 0.249642 0.249642)
							(end 0.1778 0.2794)
						)
					)
					(width 0)
					(fill yes)
				)
			)
		)
	)
	(footprint ""
		(layer "B.Cu")
		(at 452.501 -116.49202)
		(property "Reference" "C1M15"
			(at 0 0 0)
			(layer "B.SilkS")
			(hide yes)
			(effects
				(font
					(size 1.27 1.27)
				)
				(justify mirror)
			)
		)
		(property "Value" ""
			(at 0 0 0)
			(layer "B.Fab")
			(effects
				(font
					(size 1.27 1.27)
				)
				(justify mirror)
			)
		)
		(duplicate_pad_numbers_are_jumpers no)
		(fp_rect
			(start -0.3048 0.9906)
			(end 0.3048 -0.1016)
			(stroke
				(width 0)
				(type default)
			)
			(fill no)
			(layer "B.CrtYd")
		)
		(fp_line
			(start -0.3048 -0.1016)
			(end 0.3048 -0.1016)
			(stroke
				(width 0.1)
				(type default)
			)
			(layer "B.Fab")
		)
		(fp_line
			(start -0.3048 0.9906)
			(end -0.3048 -0.1016)
			(stroke
				(width 0.1)
				(type default)
			)
			(layer "B.Fab")
		)
		(fp_line
			(start 0.3048 -0.1016)
			(end 0.3048 0.9906)
			(stroke
				(width 0.1)
				(type default)
			)
			(layer "B.Fab")
		)
		(fp_line
			(start 0.3048 0.9906)
			(end -0.3048 0.9906)
			(stroke
				(width 0.1)
				(type default)
			)
			(layer "B.Fab")
		)
		(pad "1" smd rect
			(at 0 0 180)
			(size 0.508 0.508)
			(layers "B.Cu" "B.Mask" "B.Paste")
			(net "P3E_CPU0_PE3_OCP_TXN<11>")
		)
		(pad "2" smd rect
			(at 0 0.889 180)
			(size 0.508 0.508)
			(layers "B.Cu" "B.Mask" "B.Paste")
			(net "P3E_OCP_CPU0_PE3_C_TXN<11>")
		)
		(zone
			(layer "B.Cu")
			(hatch none 0.5)
			(connect_pads
				(clearance 0)
			)
			(min_thickness 0.25)
			(keepout
				(tracks allowed)
				(vias not_allowed)
				(pads allowed)
				(copperpour not_allowed)
				(footprints allowed)
			)
			(placement
				(enabled no)
				(sheetname "")
			)
			(fill
				(thermal_gap 0.5)
				(thermal_bridge_width 0.5)
				(island_removal_mode 0)
			)
			(polygon
				(pts
					(xy 452.247 -115.85702) (xy 452.755 -115.85702) (xy 452.755 -116.23802) (xy 452.247 -116.23802)
				)
			)
		)
		(zone
			(layer "B.Cu")
			(hatch none 0.5)
			(connect_pads
				(clearance 0)
			)
			(min_thickness 0.25)
			(keepout
				(tracks not_allowed)
				(vias allowed)
				(pads allowed)
				(copperpour not_allowed)
				(footprints allowed)
			)
			(placement
				(enabled no)
				(sheetname "")
			)
			(fill
				(thermal_gap 0.5)
				(thermal_bridge_width 0.5)
				(island_removal_mode 0)
			)
			(polygon
				(pts
					(xy 452.247 -115.85702) (xy 452.755 -115.85702) (xy 452.755 -116.23802) (xy 452.247 -116.23802)
				)
			)
		)
	)
	(footprint ""
		(layer "B.Cu")
		(at 28.674568 -154.559 180)
		(property "Reference" "R9L2"
			(at 0 0 0)
			(layer "B.SilkS")
			(hide yes)
			(effects
				(font
					(size 1.27 1.27)
				)
				(justify mirror)
			)
		)
		(property "Value" ""
			(at 0 0 0)
			(layer "B.Fab")
			(effects
				(font
					(size 1.27 1.27)
				)
				(justify mirror)
			)
		)
		(duplicate_pad_numbers_are_jumpers no)
		(fp_poly
			(pts
				(xy 0.2794 -0.1016) (xy -0.2794 -0.1016) (xy -0.2794 0.9906) (xy 0.2794 0.9906)
			)
			(stroke
				(width 0)
				(type default)
			)
			(fill no)
			(layer "B.CrtYd")
		)
		(fp_line
			(start 0.2794 0.9906)
			(end -0.2794 0.9906)
			(stroke
				(width 0.1)
				(type default)
			)
			(layer "B.Fab")
		)
		(fp_line
			(start 0.2794 -0.1016)
			(end 0.2794 0.9906)
			(stroke
				(width 0.1)
				(type default)
			)
			(layer "B.Fab")
		)
		(fp_line
			(start -0.2794 0.9906)
			(end -0.2794 -0.1016)
			(stroke
				(width 0.1)
				(type default)
			)
			(layer "B.Fab")
		)
		(fp_line
			(start -0.2794 -0.1016)
			(end 0.2794 -0.1016)
			(stroke
				(width 0.1)
				(type default)
			)
			(layer "B.Fab")
		)
		(pad "1" smd rect
			(at 0 0)
			(size 0.508 0.508)
			(layers "B.Cu" "B.Mask" "B.Paste")
			(net "PVDDQ_KLM")
		)
		(pad "2" smd rect
			(at 0 0.889)
			(size 0.508 0.508)
			(layers "B.Cu" "B.Mask" "B.Paste")
			(net "M_M_VREF")
		)
		(zone
			(layer "B.Cu")
			(hatch none 0.5)
			(connect_pads
				(clearance 0)
			)
			(min_thickness 0.25)
			(keepout
				(tracks not_allowed)
				(vias allowed)
				(pads allowed)
				(copperpour not_allowed)
				(footprints allowed)
			)
			(placement
				(enabled no)
				(sheetname "")
			)
			(fill
				(thermal_gap 0.5)
				(thermal_bridge_width 0.5)
				(island_removal_mode 0)
			)
			(polygon
				(pts
					(xy 28.420568 -155.194) (xy 28.928568 -155.194) (xy 28.928568 -154.813) (xy 28.420568 -154.813)
				)
			)
		)
		(zone
			(layer "B.Cu")
			(hatch none 0.5)
			(connect_pads
				(clearance 0)
			)
			(min_thickness 0.25)
			(keepout
				(tracks allowed)
				(vias not_allowed)
				(pads allowed)
				(copperpour not_allowed)
				(footprints allowed)
			)
			(placement
				(enabled no)
				(sheetname "")
			)
			(fill
				(thermal_gap 0.5)
				(thermal_bridge_width 0.5)
				(island_removal_mode 0)
			)
			(polygon
				(pts
					(xy 28.420568 -154.813) (xy 28.928568 -154.813) (xy 28.928568 -155.194) (xy 28.420568 -155.194)
				)
			)
		)
	)
	(footprint ""
		(layer "B.Cu")
		(at 433.833524 -42.91838 90)
		(property "Reference" "C1T21"
			(at 0 0 90)
			(layer "B.SilkS")
			(hide yes)
			(effects
				(font
					(size 1.27 1.27)
				)
				(justify mirror)
			)
		)
		(property "Value" ""
			(at 0 0 90)
			(layer "B.Fab")
			(effects
				(font
					(size 1.27 1.27)
				)
				(justify mirror)
			)
		)
		(duplicate_pad_numbers_are_jumpers no)
		(fp_poly
			(pts
				(xy -0.3048 -0.1016) (xy -0.3048 0.9906) (xy 0.3048 0.9906) (xy 0.3048 -0.1016)
			)
			(stroke
				(width 0)
				(type default)
			)
			(fill no)
			(layer "B.CrtYd")
		)
		(fp_line
			(start 0.3048 -0.1016)
			(end 0.3048 0.9906)
			(stroke
				(width 0.1)
				(type default)
			)
			(layer "B.Fab")
		)
		(fp_line
			(start -0.3048 -0.1016)
			(end 0.3048 -0.1016)
			(stroke
				(width 0.1)
				(type default)
			)
			(layer "B.Fab")
		)
		(fp_line
			(start 0.3048 0.9906)
			(end -0.3048 0.9906)
			(stroke
				(width 0.1)
				(type default)
			)
			(layer "B.Fab")
		)
		(fp_line
			(start -0.3048 0.9906)
			(end -0.3048 -0.1016)
			(stroke
				(width 0.1)
				(type default)
			)
			(layer "B.Fab")
		)
		(pad "1" smd rect
			(at 0 0 270)
			(size 0.508 0.508)
			(layers "B.Cu" "B.Mask" "B.Paste")
			(net "PVCCIO_CPU0")
		)
		(pad "2" smd rect
			(at 0 0.889 270)
			(size 0.508 0.508)
			(layers "B.Cu" "B.Mask" "B.Paste")
			(net "GND")
		)
		(zone
			(layer "B.Cu")
			(hatch none 0.5)
			(connect_pads
				(clearance 0)
			)
			(min_thickness 0.25)
			(keepout
				(tracks allowed)
				(vias not_allowed)
				(pads allowed)
				(copperpour not_allowed)
				(footprints allowed)
			)
			(placement
				(enabled no)
				(sheetname "")
			)
			(fill
				(thermal_gap 0.5)
				(thermal_bridge_width 0.5)
				(island_removal_mode 0)
			)
			(polygon
				(pts
					(xy 434.087524 -43.17238) (xy 434.087524 -42.66438) (xy 434.468524 -42.66438) (xy 434.468524 -43.17238)
				)
			)
		)
		(zone
			(layer "B.Cu")
			(hatch none 0.5)
			(connect_pads
				(clearance 0)
			)
			(min_thickness 0.25)
			(keepout
				(tracks not_allowed)
				(vias allowed)
				(pads allowed)
				(copperpour not_allowed)
				(footprints allowed)
			)
			(placement
				(enabled no)
				(sheetname "")
			)
			(fill
				(thermal_gap 0.5)
				(thermal_bridge_width 0.5)
				(island_removal_mode 0)
			)
			(polygon
				(pts
					(xy 434.468524 -43.17238) (xy 434.468524 -42.66438) (xy 434.087524 -42.66438) (xy 434.087524 -43.17238)
				)
			)
		)
	)
)
